# SCM (Grand Teton) — schematic netlist excerpt (pin names and nets, part order shuffled) for the footprints in the layout excerpt that follows; sources: Cadence DE-HDL packaged netlist, KiCad conversion of 12092022_DA0F0TMDCD0_F0T_Management_Board_D_brd_V3_OCP.brd

C157  Q_CAP  0.1UF 25V 10% X7R  pkg 0402  page 28 : A = P3V3_AUX ; B = GND
R568  Q_RES  220 1% CHIP  pkg 0402LF  page 49 : A = PWR_LED_P5V_AUX ; B = P5V_AUX

(kicad_pcb
	(version 20260206)
	(generator "pcbnew")
	(generator_version "10.0")
	(general
		(thickness 1.6)
		(legacy_teardrops no)
	)
	(paper "A4")
	(title_block
		(title "12092022_DA0F0TMDCD0_F0T_Management_Board_D_brd_V3_OCP.brd")
		(comment 1 "Grand Teton / footprints 1031-1032 of 1440")
	)
	(layers
		(0 "F.Cu" signal "TOP")
		(4 "In1.Cu" signal "GND")
		(6 "In2.Cu" signal "IN1")
		(8 "In3.Cu" signal "GND1")
		(10 "In4.Cu" signal "IN2")
		(12 "In5.Cu" signal "VCC")
		(14 "In6.Cu" signal "VCC1")
		(16 "In7.Cu" signal "IN3")
		(18 "In8.Cu" signal "GND2")
		(20 "In9.Cu" signal "IN4")
		(22 "In10.Cu" signal "GND3")
		(2 "B.Cu" signal "BOTTOM")
		(9 "F.Adhes" user "F.Adhesive")
		(11 "B.Adhes" user "B.Adhesive")
		(13 "F.Paste" user "Package Geometry/Pastemask Top")
		(15 "B.Paste" user "Package Geometry/Pastemask Bottom")
		(5 "F.SilkS" user "Ref Des/Silkscreen Top")
		(7 "B.SilkS" user "Ref Des/Silkscreen Bottom")
		(1 "F.Mask" user "Board Geometry/Soldermask Top")
		(3 "B.Mask" user "Board Geometry/Soldermask Bottom")
		(17 "Dwgs.User" user "User.Drawings")
		(19 "Cmts.User" user "User.Comments")
		(21 "Eco1.User" user "User.Eco1")
		(23 "Eco2.User" user "User.Eco2")
		(25 "Edge.Cuts" user "Board Geometry/Outline")
		(27 "Margin" user)
		(31 "F.CrtYd" user "Package Geometry/Place Bound Top")
		(29 "B.CrtYd" user "Package Geometry/Place Bound Bottom")
		(35 "F.Fab" user "Ref Des/Assembly Top")
		(33 "B.Fab" user "Ref Des/Assembly Bottom")
	)
	(footprint ""
		(layer "B.Cu")
		(at 49.48682 -20.71624 -90)
		(property "Reference" "C157"
			(at 0 0 90)
			(layer "B.SilkS")
			(hide yes)
			(effects
				(font
					(size 1.27 1.27)
				)
				(justify mirror)
			)
		)
		(property "Value" ""
			(at 0 0 90)
			(layer "B.Fab")
			(effects
				(font
					(size 1.27 1.27)
				)
				(justify mirror)
			)
		)
		(duplicate_pad_numbers_are_jumpers no)
		(fp_line
			(start -0.7874 0.4064)
			(end 0.7874 0.4064)
			(stroke
				(width 0.1524)
				(type default)
			)
			(layer "B.SilkS")
		)
		(fp_line
			(start 0.7874 0.4064)
			(end 0.7874 -0.4064)
			(stroke
				(width 0.1524)
				(type default)
			)
			(layer "B.SilkS")
		)
		(fp_line
			(start -0.7874 -0.4064)
			(end -0.7874 0.4064)
			(stroke
				(width 0.1524)
				(type default)
			)
			(layer "B.SilkS")
		)
		(fp_line
			(start 0.7874 -0.4064)
			(end -0.7874 -0.4064)
			(stroke
				(width 0.1524)
				(type default)
			)
			(layer "B.SilkS")
		)
		(fp_line
			(start -0.67945 0.3048)
			(end -0.120396 0.3048)
			(stroke
				(width 0.1)
				(type default)
			)
			(layer "B.Fab")
		)
		(fp_line
			(start -0.120396 0.3048)
			(end -0.120396 0.2794)
			(stroke
				(width 0.1)
				(type default)
			)
			(layer "B.Fab")
		)
		(fp_line
			(start 0.12065 0.3048)
			(end 0.67945 0.3048)
			(stroke
				(width 0.1)
				(type default)
			)
			(layer "B.Fab")
		)
		(fp_line
			(start 0.67945 0.3048)
			(end 0.67945 -0.305054)
			(stroke
				(width 0.1)
				(type default)
			)
			(layer "B.Fab")
		)
		(fp_line
			(start -0.120396 0.2794)
			(end 0.12065 0.2794)
			(stroke
				(width 0.1)
				(type default)
			)
			(layer "B.Fab")
		)
		(fp_line
			(start 0.12065 0.2794)
			(end 0.12065 0.3048)
			(stroke
				(width 0.1)
				(type default)
			)
			(layer "B.Fab")
		)
		(fp_line
			(start -0.12065 -0.2794)
			(end -0.12065 -0.3048)
			(stroke
				(width 0.1)
				(type default)
			)
			(layer "B.Fab")
		)
		(fp_line
			(start 0.12065 -0.2794)
			(end -0.12065 -0.2794)
			(stroke
				(width 0.1)
				(type default)
			)
			(layer "B.Fab")
		)
		(fp_line
			(start -0.67945 -0.3048)
			(end -0.67945 0.3048)
			(stroke
				(width 0.1)
				(type default)
			)
			(layer "B.Fab")
		)
		(fp_line
			(start -0.12065 -0.3048)
			(end -0.67945 -0.3048)
			(stroke
				(width 0.1)
				(type default)
			)
			(layer "B.Fab")
		)
		(fp_line
			(start 0.12065 -0.305054)
			(end 0.12065 -0.2794)
			(stroke
				(width 0.1)
				(type default)
			)
			(layer "B.Fab")
		)
		(fp_line
			(start 0.67945 -0.305054)
			(end 0.12065 -0.305054)
			(stroke
				(width 0.1)
				(type default)
			)
			(layer "B.Fab")
		)
		(pad "1" smd circle
			(at 0.40005 0 90)
			(size 0 0)
			(layers "B.Cu" "B.Mask" "B.Paste")
			(net "P3V3_AUX")
		)
		(pad "2" smd circle
			(at -0.40005 0 90)
			(size 0 0)
			(layers "B.Cu" "B.Mask" "B.Paste")
			(net "GND")
		)
	)
	(footprint ""
		(layer "B.Cu")
		(at 14.097 -18.161 -90)
		(property "Reference" "R568"
			(at 0 0 90)
			(layer "B.SilkS")
			(hide yes)
			(effects
				(font
					(size 1.27 1.27)
				)
				(justify mirror)
			)
		)
		(property "Value" ""
			(at 0 0 90)
			(layer "B.Fab")
			(effects
				(font
					(size 1.27 1.27)
				)
				(justify mirror)
			)
		)
		(duplicate_pad_numbers_are_jumpers no)
		(fp_line
			(start -0.7874 0.4064)
			(end 0.7874 0.4064)
			(stroke
				(width 0.1524)
				(type default)
			)
			(layer "B.SilkS")
		)
		(fp_line
			(start 0.7874 0.4064)
			(end 0.7874 -0.4064)
			(stroke
				(width 0.1524)
				(type default)
			)
			(layer "B.SilkS")
		)
		(fp_line
			(start -0.7874 -0.4064)
			(end -0.7874 0.4064)
			(stroke
				(width 0.1524)
				(type default)
			)
			(layer "B.SilkS")
		)
		(fp_line
			(start 0.7874 -0.4064)
			(end -0.7874 -0.4064)
			(stroke
				(width 0.1524)
				(type default)
			)
			(layer "B.SilkS")
		)
		(fp_line
			(start -0.67945 0.3048)
			(end -0.120396 0.3048)
			(stroke
				(width 0.1)
				(type default)
			)
			(layer "B.Fab")
		)
		(fp_line
			(start -0.120396 0.3048)
			(end -0.120396 0.2794)
			(stroke
				(width 0.1)
				(type default)
			)
			(layer "B.Fab")
		)
		(fp_line
			(start 0.12065 0.3048)
			(end 0.67945 0.3048)
			(stroke
				(width 0.1)
				(type default)
			)
			(layer "B.Fab")
		)
		(fp_line
			(start 0.67945 0.3048)
			(end 0.67945 -0.305054)
			(stroke
				(width 0.1)
				(type default)
			)
			(layer "B.Fab")
		)
		(fp_line
			(start -0.120396 0.2794)
			(end 0.12065 0.2794)
			(stroke
				(width 0.1)
				(type default)
			)
			(layer "B.Fab")
		)
		(fp_line
			(start 0.12065 0.2794)
			(end 0.12065 0.3048)
			(stroke
				(width 0.1)
				(type default)
			)
			(layer "B.Fab")
		)
		(fp_line
			(start -0.12065 -0.2794)
			(end -0.12065 -0.3048)
			(stroke
				(width 0.1)
				(type default)
			)
			(layer "B.Fab")
		)
		(fp_line
			(start 0.12065 -0.2794)
			(end -0.12065 -0.2794)
			(stroke
				(width 0.1)
				(type default)
			)
			(layer "B.Fab")
		)
		(fp_line
			(start -0.67945 -0.3048)
			(end -0.67945 0.3048)
			(stroke
				(width 0.1)
				(type default)
			)
			(layer "B.Fab")
		)
		(fp_line
			(start -0.12065 -0.3048)
			(end -0.67945 -0.3048)
			(stroke
				(width 0.1)
				(type default)
			)
			(layer "B.Fab")
		)
		(fp_line
			(start 0.12065 -0.305054)
			(end 0.12065 -0.2794)
			(stroke
				(width 0.1)
				(type default)
			)
			(layer "B.Fab")
		)
		(fp_line
			(start 0.67945 -0.305054)
			(end 0.12065 -0.305054)
			(stroke
				(width 0.1)
				(type default)
			)
			(layer "B.Fab")
		)
		(pad "1" smd circle
			(at 0.40005 0 90)
			(size 0 0)
			(layers "B.Cu" "B.Mask" "B.Paste")
			(net "PWR_LED_P5V_AUX")
		)
		(pad "2" smd circle
			(at -0.40005 0 90)
			(size 0 0)
			(layers "B.Cu" "B.Mask" "B.Paste")
			(net "P5V_AUX")
		)
	)
)
